# T6G (Grand Teton) — schematic netlist excerpt (pin names and nets, part order shuffled) for the footprints in the layout excerpt that follows; sources: Cadence DE-HDL packaged netlist, KiCad conversion of 04192023_DAF0TMB3IC0_F0TG_MB_C_brd_V02_OCP.brd

C689  Q_CAP_DIFFBUS  DIFF BUS_0.22UF 6.3V 20% X6S  pkg C0201  page 67 : \1\ = P5E_CPU1_G1_TX_C_DP<10> ; \2\ = P5E_CPU1_G1_TX_DP<10>
R978  Q_RES  4.7K 5% EMPTY  pkg 0201LF  page 276 : A = P1V8_CPU0_RT_1D ; B = GPIO2_RT_CPU0_P0
PR349  Q_RES  5.6 1% CHIP  pkg 0402LF  page 195 : A = SW_PVDDCR_CPU0_P0_BOOT4 ; B = SW_PVDDCR_CPU0_P0_BOOT4_RC

(kicad_pcb
	(version 20260206)
	(generator "pcbnew")
	(generator_version "10.0")
	(general
		(thickness 1.6)
		(legacy_teardrops no)
	)
	(paper "A4")
	(title_block
		(title "04192023_DAF0TMB3IC0_F0TG_MB_C_brd_V02_OCP.brd")
		(comment 1 "Grand Teton / footprints 598-600 of 8354")
	)
	(layers
		(0 "F.Cu" signal "TOP")
		(4 "In1.Cu" signal "GND")
		(6 "In2.Cu" signal "IN1")
		(8 "In3.Cu" signal "GND1")
		(10 "In4.Cu" signal "IN2")
		(12 "In5.Cu" signal "GND2")
		(14 "In6.Cu" signal "IN3")
		(16 "In7.Cu" signal "GND3")
		(18 "In8.Cu" signal "VCC")
		(20 "In9.Cu" signal "VCC1")
		(22 "In10.Cu" signal "GND4")
		(24 "In11.Cu" signal "IN4")
		(26 "In12.Cu" signal "GND5")
		(28 "In13.Cu" signal "IN5")
		(30 "In14.Cu" signal "GND6")
		(32 "In15.Cu" signal "IN6")
		(34 "In16.Cu" signal "GND7")
		(2 "B.Cu" signal "BOTTOM")
		(9 "F.Adhes" user "F.Adhesive")
		(11 "B.Adhes" user "B.Adhesive")
		(13 "F.Paste" user "Package Geometry/Pastemask Top")
		(15 "B.Paste" user "Package Geometry/Pastemask Bottom")
		(5 "F.SilkS" user "Ref Des/Silkscreen Top")
		(7 "B.SilkS" user "Ref Des/Silkscreen Bottom")
		(1 "F.Mask" user "Board Geometry/Soldermask Top")
		(3 "B.Mask" user "Board Geometry/Soldermask Bottom")
		(17 "Dwgs.User" user "User.Drawings")
		(19 "Cmts.User" user "User.Comments")
		(21 "Eco1.User" user "User.Eco1")
		(23 "Eco2.User" user "User.Eco2")
		(25 "Edge.Cuts" user "Board Geometry/Outline")
		(27 "Margin" user)
		(31 "F.CrtYd" user "Package Geometry/Place Bound Top")
		(29 "B.CrtYd" user "Package Geometry/Place Bound Bottom")
		(35 "F.Fab" user "Ref Des/Assembly Top")
		(33 "B.Fab" user "Ref Des/Assembly Bottom")
	)
	(footprint ""
		(layer "F.Cu")
		(at 30.392878 -17.623536 90)
		(property "Reference" "C689"
			(at 0 0 90)
			(layer "F.SilkS")
			(hide yes)
			(effects
				(font
					(size 1.27 1.27)
				)
			)
		)
		(property "Value" ""
			(at 0 0 90)
			(layer "F.Fab")
			(effects
				(font
					(size 1.27 1.27)
				)
			)
		)
		(duplicate_pad_numbers_are_jumpers no)
		(fp_line
			(start 0.299974 -0.150114)
			(end 0.299974 0.150114)
			(stroke
				(width 0.1)
				(type default)
			)
			(layer "F.Fab")
		)
		(fp_line
			(start -0.299974 -0.150114)
			(end 0.299974 -0.150114)
			(stroke
				(width 0.1)
				(type default)
			)
			(layer "F.Fab")
		)
		(fp_line
			(start 0.299974 0.150114)
			(end -0.299974 0.150114)
			(stroke
				(width 0.1)
				(type default)
			)
			(layer "F.Fab")
		)
		(fp_line
			(start -0.299974 0.150114)
			(end -0.299974 -0.150114)
			(stroke
				(width 0.1)
				(type default)
			)
			(layer "F.Fab")
		)
		(pad "1" smd rect
			(at -0.2667 0 90)
			(size 0.3048 0.381)
			(layers "F.Cu" "F.Mask" "F.Paste")
			(net "P5E_CPU1_G1_TX_C_DP<10>")
		)
		(pad "2" smd rect
			(at 0.2667 0 90)
			(size 0.3048 0.381)
			(layers "F.Cu" "F.Mask" "F.Paste")
			(net "P5E_CPU1_G1_TX_DP<10>")
		)
	)
	(footprint ""
		(layer "F.Cu")
		(at 388.649972 -178.0921 -90)
		(property "Reference" "PR349"
			(at 0 0 270)
			(layer "F.SilkS")
			(hide yes)
			(effects
				(font
					(size 1.27 1.27)
				)
			)
		)
		(property "Value" ""
			(at 0 0 270)
			(layer "F.Fab")
			(effects
				(font
					(size 1.27 1.27)
				)
			)
		)
		(duplicate_pad_numbers_are_jumpers no)
		(fp_line
			(start -0.7874 0.4064)
			(end -0.7874 -0.4064)
			(stroke
				(width 0.1524)
				(type default)
			)
			(layer "F.SilkS")
		)
		(fp_line
			(start 0.7874 0.4064)
			(end -0.7874 0.4064)
			(stroke
				(width 0.1524)
				(type default)
			)
			(layer "F.SilkS")
		)
		(fp_line
			(start -0.7874 -0.4064)
			(end 0.7874 -0.4064)
			(stroke
				(width 0.1524)
				(type default)
			)
			(layer "F.SilkS")
		)
		(fp_line
			(start 0.7874 -0.4064)
			(end 0.7874 0.4064)
			(stroke
				(width 0.1524)
				(type default)
			)
			(layer "F.SilkS")
		)
		(fp_line
			(start -0.67945 0.3048)
			(end -0.67945 -0.305054)
			(stroke
				(width 0.1)
				(type default)
			)
			(layer "F.Fab")
		)
		(fp_line
			(start -0.12065 0.3048)
			(end -0.67945 0.3048)
			(stroke
				(width 0.1)
				(type default)
			)
			(layer "F.Fab")
		)
		(fp_line
			(start 0.120396 0.3048)
			(end 0.120396 0.2794)
			(stroke
				(width 0.1)
				(type default)
			)
			(layer "F.Fab")
		)
		(fp_line
			(start 0.67945 0.3048)
			(end 0.120396 0.3048)
			(stroke
				(width 0.1)
				(type default)
			)
			(layer "F.Fab")
		)
		(fp_line
			(start -0.12065 0.2794)
			(end -0.12065 0.3048)
			(stroke
				(width 0.1)
				(type default)
			)
			(layer "F.Fab")
		)
		(fp_line
			(start 0.120396 0.2794)
			(end -0.12065 0.2794)
			(stroke
				(width 0.1)
				(type default)
			)
			(layer "F.Fab")
		)
		(fp_line
			(start -0.12065 -0.2794)
			(end 0.12065 -0.2794)
			(stroke
				(width 0.1)
				(type default)
			)
			(layer "F.Fab")
		)
		(fp_line
			(start 0.12065 -0.2794)
			(end 0.12065 -0.3048)
			(stroke
				(width 0.1)
				(type default)
			)
			(layer "F.Fab")
		)
		(fp_line
			(start 0.12065 -0.3048)
			(end 0.67945 -0.3048)
			(stroke
				(width 0.1)
				(type default)
			)
			(layer "F.Fab")
		)
		(fp_line
			(start 0.67945 -0.3048)
			(end 0.67945 0.3048)
			(stroke
				(width 0.1)
				(type default)
			)
			(layer "F.Fab")
		)
		(fp_line
			(start -0.67945 -0.305054)
			(end -0.12065 -0.305054)
			(stroke
				(width 0.1)
				(type default)
			)
			(layer "F.Fab")
		)
		(fp_line
			(start -0.12065 -0.305054)
			(end -0.12065 -0.2794)
			(stroke
				(width 0.1)
				(type default)
			)
			(layer "F.Fab")
		)
		(pad "1" smd circle
			(at -0.40005 0 270)
			(size 0 0)
			(layers "F.Cu" "F.Mask" "F.Paste")
			(net "SW_PVDDCR_CPU0_P0_BOOT4")
		)
		(pad "2" smd circle
			(at 0.40005 0 270)
			(size 0 0)
			(layers "F.Cu" "F.Mask" "F.Paste")
			(net "SW_PVDDCR_CPU0_P0_BOOT4_RC")
		)
	)
	(footprint ""
		(layer "F.Cu")
		(at 297.995594 -393.96416)
		(property "Reference" "R978"
			(at 0 0 0)
			(layer "F.SilkS")
			(hide yes)
			(effects
				(font
					(size 1.27 1.27)
				)
			)
		)
		(property "Value" ""
			(at 0 0 0)
			(layer "F.Fab")
			(effects
				(font
					(size 1.27 1.27)
				)
			)
		)
		(duplicate_pad_numbers_are_jumpers no)
		(fp_line
			(start -0.32512 -0.175006)
			(end 0.32512 -0.175006)
			(stroke
				(width 0.1)
				(type default)
			)
			(layer "F.Fab")
		)
		(fp_line
			(start -0.32512 0.175006)
			(end -0.32512 -0.175006)
			(stroke
				(width 0.1)
				(type default)
			)
			(layer "F.Fab")
		)
		(fp_line
			(start 0.32512 -0.175006)
			(end 0.32512 0.175006)
			(stroke
				(width 0.1)
				(type default)
			)
			(layer "F.Fab")
		)
		(fp_line
			(start 0.32512 0.175006)
			(end -0.32512 0.175006)
			(stroke
				(width 0.1)
				(type default)
			)
			(layer "F.Fab")
		)
		(pad "1" smd rect
			(at -0.2667 0)
			(size 0.3048 0.381)
			(layers "F.Cu" "F.Mask" "F.Paste")
			(net "P1V8_CPU0_RT_1D")
		)
		(pad "2" smd rect
			(at 0.2667 0 180)
			(size 0.3048 0.381)
			(layers "F.Cu" "F.Mask" "F.Paste")
			(net "GPIO2_RT_CPU0_P0")
		)
	)
)
